(kicad_pcb
	(version 20260206)
	(generator "pcbnew")
	(generator_version "10.0")
	(general
		(thickness 1.6)
		(legacy_teardrops no)
	)
	(paper "A4")
	(title_block
		(title "03242023_DA0F0TMBIJ0_F0T_Motherboard_J_brd_V01_OCP.brd")
		(comment 1 "Grand Teton / footprint 3198 of 6105 (J12), pads 1-112 of 291")
	)
	(layers
		(0 "F.Cu" signal "TOP")
		(4 "In1.Cu" signal "GND")
		(6 "In2.Cu" signal "IN1")
		(8 "In3.Cu" signal "GND1")
		(10 "In4.Cu" signal "IN2")
		(12 "In5.Cu" signal "GND2")
		(14 "In6.Cu" signal "IN3")
		(16 "In7.Cu" signal "GND3")
		(18 "In8.Cu" signal "VCC")
		(20 "In9.Cu" signal "VCC1")
		(22 "In10.Cu" signal "GND4")
		(24 "In11.Cu" signal "IN4")
		(26 "In12.Cu" signal "GND5")
		(28 "In13.Cu" signal "IN5")
		(30 "In14.Cu" signal "GND6")
		(32 "In15.Cu" signal "IN6")
		(34 "In16.Cu" signal "GND7")
		(2 "B.Cu" signal "BOTTOM")
		(9 "F.Adhes" user "F.Adhesive")
		(11 "B.Adhes" user "B.Adhesive")
		(13 "F.Paste" user "Package Geometry/Pastemask Top")
		(15 "B.Paste" user "Package Geometry/Pastemask Bottom")
		(5 "F.SilkS" user "Ref Des/Silkscreen Top")
		(7 "B.SilkS" user "Ref Des/Silkscreen Bottom")
		(1 "F.Mask" user "Board Geometry/Soldermask Top")
		(3 "B.Mask" user "Board Geometry/Soldermask Bottom")
		(17 "Dwgs.User" user "User.Drawings")
		(19 "Cmts.User" user "User.Comments")
		(21 "Eco1.User" user "User.Eco1")
		(23 "Eco2.User" user "User.Eco2")
		(25 "Edge.Cuts" user "Board Geometry/Outline")
		(27 "Margin" user)
		(31 "F.CrtYd" user "Package Geometry/Place Bound Top")
		(29 "B.CrtYd" user "Package Geometry/Place Bound Bottom")
		(35 "F.Fab" user "Ref Des/Assembly Top")
		(33 "B.Fab" user "Ref Des/Assembly Bottom")
	)
	(footprint ""
		(layer "F.Cu")
		(at 423.890948 -258.091686)
		(property "Reference" "J12"
			(at -3.683 -81.702148 0)
			(unlocked yes)
			(layer "F.SilkS")
			(effects
				(font
					(size 0.7874 0.5842)
					(thickness 0.1524)
				)
				(justify left)
			)
		)
		(property "Value" ""
			(at 0 0 0)
			(layer "F.Fab")
			(effects
				(font
					(size 1.27 1.27)
				)
			)
		)
		(duplicate_pad_numbers_are_jumpers no)
		(pad "1" smd rect
			(at -2.050034 -63.324994 270)
			(size 0.519938 1.4986)
			(layers "F.Cu" "F.Mask" "F.Paste")
			(net "P12V_S3_AUX_CPU0_NVDIMM")
		)
		(pad "2" smd rect
			(at -2.050034 -62.47511 270)
			(size 0.519938 1.4986)
			(layers "F.Cu" "F.Mask" "F.Paste")
			(net "TP_CHF_CPU0_DIMM2_FRU_0")
		)
		(pad "3" smd rect
			(at -2.050034 -61.624972 270)
			(size 0.519938 1.4986)
			(layers "F.Cu" "F.Mask" "F.Paste")
			(net "P3V3_AUX")
		)
		(pad "4" smd rect
			(at -2.050034 -60.775088 270)
			(size 0.519938 1.4986)
			(layers "F.Cu" "F.Mask" "F.Paste")
			(net "I3C_SPD_DDREFGH_CPU0_LVC1_SCL_3")
		)
		(pad "5" smd rect
			(at -2.050034 -59.92495 270)
			(size 0.519938 1.4986)
			(layers "F.Cu" "F.Mask" "F.Paste")
			(net "I3C_SPD_DDREFGH_CPU0_LVC1_SDA")
		)
		(pad "6" smd rect
			(at -2.050034 -59.075066 270)
			(size 0.519938 1.4986)
			(layers "F.Cu" "F.Mask" "F.Paste")
			(net "GND")
		)
		(pad "7" smd rect
			(at -2.050034 -58.224928 270)
			(size 0.519938 1.4986)
			(layers "F.Cu" "F.Mask" "F.Paste")
			(net "M_F_CPU0_SA_DQ<0>")
		)
		(pad "8" smd rect
			(at -2.050034 -57.375044 270)
			(size 0.519938 1.4986)
			(layers "F.Cu" "F.Mask" "F.Paste")
			(net "GND")
		)
		(pad "9" smd rect
			(at -2.050034 -56.524906 270)
			(size 0.519938 1.4986)
			(layers "F.Cu" "F.Mask" "F.Paste")
			(net "M_F_CPU0_SA_DQ<1>")
		)
		(pad "10" smd rect
			(at -2.050034 -55.675022 270)
			(size 0.519938 1.4986)
			(layers "F.Cu" "F.Mask" "F.Paste")
			(net "GND")
		)
		(pad "11" smd rect
			(at -2.050034 -54.824884 270)
			(size 0.519938 1.4986)
			(layers "F.Cu" "F.Mask" "F.Paste")
			(net "M_F_CPU0_SA_DQS_DP<0>")
		)
		(pad "12" smd rect
			(at -2.050034 -53.975 270)
			(size 0.519938 1.4986)
			(layers "F.Cu" "F.Mask" "F.Paste")
			(net "M_F_CPU0_SA_DQS_DN<0>")
		)
		(pad "13" smd rect
			(at -2.050034 -53.125116 270)
			(size 0.519938 1.4986)
			(layers "F.Cu" "F.Mask" "F.Paste")
			(net "GND")
		)
		(pad "14" smd rect
			(at -2.050034 -52.274978 270)
			(size 0.519938 1.4986)
			(layers "F.Cu" "F.Mask" "F.Paste")
			(net "M_F_CPU0_SA_DQ<4>")
		)
		(pad "15" smd rect
			(at -2.050034 -51.425094 270)
			(size 0.519938 1.4986)
			(layers "F.Cu" "F.Mask" "F.Paste")
			(net "GND")
		)
		(pad "16" smd rect
			(at -2.050034 -50.574956 270)
			(size 0.519938 1.4986)
			(layers "F.Cu" "F.Mask" "F.Paste")
			(net "M_F_CPU0_SA_DQ<5>")
		)
		(pad "17" smd rect
			(at -2.050034 -49.725072 270)
			(size 0.519938 1.4986)
			(layers "F.Cu" "F.Mask" "F.Paste")
			(net "GND")
		)
		(pad "18" smd rect
			(at -2.050034 -48.874934 270)
			(size 0.519938 1.4986)
			(layers "F.Cu" "F.Mask" "F.Paste")
			(net "M_F_CPU0_SA_DQ<8>")
		)
		(pad "19" smd rect
			(at -2.050034 -48.02505 270)
			(size 0.519938 1.4986)
			(layers "F.Cu" "F.Mask" "F.Paste")
			(net "GND")
		)
		(pad "20" smd rect
			(at -2.050034 -47.174912 270)
			(size 0.519938 1.4986)
			(layers "F.Cu" "F.Mask" "F.Paste")
			(net "M_F_CPU0_SA_DQ<9>")
		)
		(pad "21" smd rect
			(at -2.050034 -46.325028 270)
			(size 0.519938 1.4986)
			(layers "F.Cu" "F.Mask" "F.Paste")
			(net "GND")
		)
		(pad "22" smd rect
			(at -2.050034 -45.47489 270)
			(size 0.519938 1.4986)
			(layers "F.Cu" "F.Mask" "F.Paste")
			(net "M_F_CPU0_SA_DQS_DP<1>")
		)
		(pad "23" smd rect
			(at -2.050034 -44.625006 270)
			(size 0.519938 1.4986)
			(layers "F.Cu" "F.Mask" "F.Paste")
			(net "M_F_CPU0_SA_DQS_DN<1>")
		)
		(pad "24" smd rect
			(at -2.050034 -43.775122 270)
			(size 0.519938 1.4986)
			(layers "F.Cu" "F.Mask" "F.Paste")
			(net "GND")
		)
		(pad "25" smd rect
			(at -2.050034 -42.924984 270)
			(size 0.519938 1.4986)
			(layers "F.Cu" "F.Mask" "F.Paste")
			(net "M_F_CPU0_SA_DQ<12>")
		)
		(pad "26" smd rect
			(at -2.050034 -42.0751 270)
			(size 0.519938 1.4986)
			(layers "F.Cu" "F.Mask" "F.Paste")
			(net "GND")
		)
		(pad "27" smd rect
			(at -2.050034 -41.224962 270)
			(size 0.519938 1.4986)
			(layers "F.Cu" "F.Mask" "F.Paste")
			(net "M_F_CPU0_SA_DQ<13>")
		)
		(pad "28" smd rect
			(at -2.050034 -40.375078 270)
			(size 0.519938 1.4986)
			(layers "F.Cu" "F.Mask" "F.Paste")
			(net "GND")
		)
		(pad "29" smd rect
			(at -2.050034 -39.52494 270)
			(size 0.519938 1.4986)
			(layers "F.Cu" "F.Mask" "F.Paste")
			(net "M_F_CPU0_SA_DQ<16>")
		)
		(pad "30" smd rect
			(at -2.050034 -38.675056 270)
			(size 0.519938 1.4986)
			(layers "F.Cu" "F.Mask" "F.Paste")
			(net "GND")
		)
		(pad "31" smd rect
			(at -2.050034 -37.824918 270)
			(size 0.519938 1.4986)
			(layers "F.Cu" "F.Mask" "F.Paste")
			(net "M_F_CPU0_SA_DQ<17>")
		)
		(pad "32" smd rect
			(at -2.050034 -36.975034 270)
			(size 0.519938 1.4986)
			(layers "F.Cu" "F.Mask" "F.Paste")
			(net "GND")
		)
		(pad "33" smd rect
			(at -2.050034 -36.124896 270)
			(size 0.519938 1.4986)
			(layers "F.Cu" "F.Mask" "F.Paste")
			(net "M_F_CPU0_SA_DQS_DP<2>")
		)
		(pad "34" smd rect
			(at -2.050034 -35.275012 270)
			(size 0.519938 1.4986)
			(layers "F.Cu" "F.Mask" "F.Paste")
			(net "M_F_CPU0_SA_DQS_DN<2>")
		)
		(pad "35" smd rect
			(at -2.050034 -34.425128 270)
			(size 0.519938 1.4986)
			(layers "F.Cu" "F.Mask" "F.Paste")
			(net "GND")
		)
		(pad "36" smd rect
			(at -2.050034 -33.57499 270)
			(size 0.519938 1.4986)
			(layers "F.Cu" "F.Mask" "F.Paste")
			(net "M_F_CPU0_SA_DQ<20>")
		)
		(pad "37" smd rect
			(at -2.050034 -32.725106 270)
			(size 0.519938 1.4986)
			(layers "F.Cu" "F.Mask" "F.Paste")
			(net "GND")
		)
		(pad "38" smd rect
			(at -2.050034 -31.874968 270)
			(size 0.519938 1.4986)
			(layers "F.Cu" "F.Mask" "F.Paste")
			(net "M_F_CPU0_SA_DQ<21>")
		)
		(pad "39" smd rect
			(at -2.050034 -31.025084 270)
			(size 0.519938 1.4986)
			(layers "F.Cu" "F.Mask" "F.Paste")
			(net "GND")
		)
		(pad "40" smd rect
			(at -2.050034 -30.174946 270)
			(size 0.519938 1.4986)
			(layers "F.Cu" "F.Mask" "F.Paste")
			(net "M_F_CPU0_SA_DQ<24>")
		)
		(pad "41" smd rect
			(at -2.050034 -29.325062 270)
			(size 0.519938 1.4986)
			(layers "F.Cu" "F.Mask" "F.Paste")
			(net "GND")
		)
		(pad "42" smd rect
			(at -2.050034 -28.474924 270)
			(size 0.519938 1.4986)
			(layers "F.Cu" "F.Mask" "F.Paste")
			(net "M_F_CPU0_SA_DQ<25>")
		)
		(pad "43" smd rect
			(at -2.050034 -27.62504 270)
			(size 0.519938 1.4986)
			(layers "F.Cu" "F.Mask" "F.Paste")
			(net "GND")
		)
		(pad "44" smd rect
			(at -2.050034 -26.774902 270)
			(size 0.519938 1.4986)
			(layers "F.Cu" "F.Mask" "F.Paste")
			(net "M_F_CPU0_SA_DQS_DP<3>")
		)
		(pad "45" smd rect
			(at -2.050034 -25.925018 270)
			(size 0.519938 1.4986)
			(layers "F.Cu" "F.Mask" "F.Paste")
			(net "M_F_CPU0_SA_DQS_DN<3>")
		)
		(pad "46" smd rect
			(at -2.050034 -25.07488 270)
			(size 0.519938 1.4986)
			(layers "F.Cu" "F.Mask" "F.Paste")
			(net "GND")
		)
		(pad "47" smd rect
			(at -2.050034 -24.224996 270)
			(size 0.519938 1.4986)
			(layers "F.Cu" "F.Mask" "F.Paste")
			(net "M_F_CPU0_SA_DQ<28>")
		)
		(pad "48" smd rect
			(at -2.050034 -23.375112 270)
			(size 0.519938 1.4986)
			(layers "F.Cu" "F.Mask" "F.Paste")
			(net "GND")
		)
		(pad "49" smd rect
			(at -2.050034 -22.524974 270)
			(size 0.519938 1.4986)
			(layers "F.Cu" "F.Mask" "F.Paste")
			(net "M_F_CPU0_SA_DQ<29>")
		)
		(pad "50" smd rect
			(at -2.050034 -21.67509 270)
			(size 0.519938 1.4986)
			(layers "F.Cu" "F.Mask" "F.Paste")
			(net "GND")
		)
		(pad "51" smd rect
			(at -2.050034 -20.824952 270)
			(size 0.519938 1.4986)
			(layers "F.Cu" "F.Mask" "F.Paste")
			(net "M_F_CPU0_SA_CB<0>")
		)
		(pad "52" smd rect
			(at -2.050034 -19.975068 270)
			(size 0.519938 1.4986)
			(layers "F.Cu" "F.Mask" "F.Paste")
			(net "GND")
		)
		(pad "53" smd rect
			(at -2.050034 -19.12493 270)
			(size 0.519938 1.4986)
			(layers "F.Cu" "F.Mask" "F.Paste")
			(net "M_F_CPU0_SA_CB<1>")
		)
		(pad "54" smd rect
			(at -2.050034 -18.275046 270)
			(size 0.519938 1.4986)
			(layers "F.Cu" "F.Mask" "F.Paste")
			(net "GND")
		)
		(pad "55" smd rect
			(at -2.050034 -17.424908 270)
			(size 0.519938 1.4986)
			(layers "F.Cu" "F.Mask" "F.Paste")
			(net "M_F_CPU0_SA_DQS_DP<4>")
		)
		(pad "56" smd rect
			(at -2.050034 -16.575024 270)
			(size 0.519938 1.4986)
			(layers "F.Cu" "F.Mask" "F.Paste")
			(net "M_F_CPU0_SA_DQS_DN<4>")
		)
		(pad "57" smd rect
			(at -2.050034 -15.724886 270)
			(size 0.519938 1.4986)
			(layers "F.Cu" "F.Mask" "F.Paste")
			(net "GND")
		)
		(pad "58" smd rect
			(at -2.050034 -14.875002 270)
			(size 0.519938 1.4986)
			(layers "F.Cu" "F.Mask" "F.Paste")
			(net "M_F_CPU0_SA_CB<4>")
		)
		(pad "59" smd rect
			(at -2.050034 -14.025118 270)
			(size 0.519938 1.4986)
			(layers "F.Cu" "F.Mask" "F.Paste")
			(net "GND")
		)
		(pad "60" smd rect
			(at -2.050034 -13.17498 270)
			(size 0.519938 1.4986)
			(layers "F.Cu" "F.Mask" "F.Paste")
			(net "M_F_CPU0_SA_CB<5>")
		)
		(pad "61" smd rect
			(at -2.050034 -12.325096 270)
			(size 0.519938 1.4986)
			(layers "F.Cu" "F.Mask" "F.Paste")
			(net "GND")
		)
		(pad "62" smd rect
			(at -2.050034 -11.474958 270)
			(size 0.519938 1.4986)
			(layers "F.Cu" "F.Mask" "F.Paste")
			(net "M_F_CPU0_ALERT_N")
		)
		(pad "63" smd rect
			(at -2.050034 -10.625074 270)
			(size 0.519938 1.4986)
			(layers "F.Cu" "F.Mask" "F.Paste")
			(net "GND")
		)
		(pad "64" smd rect
			(at -2.050034 -9.774936 270)
			(size 0.519938 1.4986)
			(layers "F.Cu" "F.Mask" "F.Paste")
			(net "M_F_CPU0_SA_CS_N<2>")
		)
		(pad "65" smd rect
			(at -2.050034 -8.925052 270)
			(size 0.519938 1.4986)
			(layers "F.Cu" "F.Mask" "F.Paste")
			(net "GND")
		)
		(pad "66" smd rect
			(at -2.050034 -8.074914 270)
			(size 0.519938 1.4986)
			(layers "F.Cu" "F.Mask" "F.Paste")
			(net "M_F_CPU0_SA_CA<0>")
		)
		(pad "67" smd rect
			(at -2.050034 -7.22503 270)
			(size 0.519938 1.4986)
			(layers "F.Cu" "F.Mask" "F.Paste")
			(net "GND")
		)
		(pad "68" smd rect
			(at -2.050034 -6.374892 270)
			(size 0.519938 1.4986)
			(layers "F.Cu" "F.Mask" "F.Paste")
			(net "M_F_CPU0_SA_CA<2>")
		)
		(pad "69" smd rect
			(at -2.050034 -5.525008 270)
			(size 0.519938 1.4986)
			(layers "F.Cu" "F.Mask" "F.Paste")
			(net "GND")
		)
		(pad "70" smd rect
			(at -2.050034 -4.675124 270)
			(size 0.519938 1.4986)
			(layers "F.Cu" "F.Mask" "F.Paste")
			(net "M_F_CPU0_SA_CA<4>")
		)
		(pad "71" smd rect
			(at -2.050034 -3.824986 270)
			(size 0.519938 1.4986)
			(layers "F.Cu" "F.Mask" "F.Paste")
			(net "GND")
		)
		(pad "72" smd rect
			(at -2.050034 -2.975102 270)
			(size 0.519938 1.4986)
			(layers "F.Cu" "F.Mask" "F.Paste")
			(net "M_F_CPU0_SA_CA<6>")
		)
		(pad "73" smd rect
			(at -2.050034 -2.124964 270)
			(size 0.519938 1.4986)
			(layers "F.Cu" "F.Mask" "F.Paste")
			(net "GND")
		)
		(pad "74" smd rect
			(at -2.050034 -1.27508 270)
			(size 0.519938 1.4986)
			(layers "F.Cu" "F.Mask" "F.Paste")
			(net "M_F_CPU0_SA_PAR")
		)
		(pad "75" smd rect
			(at -2.050034 -0.424942 270)
			(size 0.519938 1.4986)
			(layers "F.Cu" "F.Mask" "F.Paste")
			(net "GND")
		)
		(pad "76" smd rect
			(at -2.050034 5.525008 270)
			(size 0.519938 1.4986)
			(layers "F.Cu" "F.Mask" "F.Paste")
			(net "M_F_CPU0_SB_CA<0>")
		)
		(pad "77" smd rect
			(at -2.050034 6.374892 270)
			(size 0.519938 1.4986)
			(layers "F.Cu" "F.Mask" "F.Paste")
			(net "GND")
		)
		(pad "78" smd rect
			(at -2.050034 7.22503 270)
			(size 0.519938 1.4986)
			(layers "F.Cu" "F.Mask" "F.Paste")
			(net "M_F_CPU0_SB_CA<2>")
		)
		(pad "79" smd rect
			(at -2.050034 8.074914 270)
			(size 0.519938 1.4986)
			(layers "F.Cu" "F.Mask" "F.Paste")
			(net "GND")
		)
		(pad "80" smd rect
			(at -2.050034 8.925052 270)
			(size 0.519938 1.4986)
			(layers "F.Cu" "F.Mask" "F.Paste")
			(net "M_F_CPU0_SB_CA<4>")
		)
		(pad "81" smd rect
			(at -2.050034 9.774936 270)
			(size 0.519938 1.4986)
			(layers "F.Cu" "F.Mask" "F.Paste")
			(net "GND")
		)
		(pad "82" smd rect
			(at -2.050034 10.625074 270)
			(size 0.519938 1.4986)
			(layers "F.Cu" "F.Mask" "F.Paste")
			(net "M_F_CPU0_SB_CA<6>")
		)
		(pad "83" smd rect
			(at -2.050034 11.474958 270)
			(size 0.519938 1.4986)
			(layers "F.Cu" "F.Mask" "F.Paste")
			(net "GND")
		)
		(pad "84" smd rect
			(at -2.050034 12.325096 270)
			(size 0.519938 1.4986)
			(layers "F.Cu" "F.Mask" "F.Paste")
			(net "M_F_CPU0_SB_CS_N<2>")
		)
		(pad "85" smd rect
			(at -2.050034 13.17498 270)
			(size 0.519938 1.4986)
			(layers "F.Cu" "F.Mask" "F.Paste")
			(net "GND")
		)
		(pad "86" smd rect
			(at -2.050034 14.025118 270)
			(size 0.519938 1.4986)
			(layers "F.Cu" "F.Mask" "F.Paste")
			(net "M_F_CPU0_SA_RSP<1>")
		)
		(pad "87" smd rect
			(at -2.050034 14.875002 270)
			(size 0.519938 1.4986)
			(layers "F.Cu" "F.Mask" "F.Paste")
			(net "M_F_CPU0_SB_RSP<1>")
		)
		(pad "88" smd rect
			(at -2.050034 15.724886 270)
			(size 0.519938 1.4986)
			(layers "F.Cu" "F.Mask" "F.Paste")
			(net "GND")
		)
		(pad "89" smd rect
			(at -2.050034 16.575024 270)
			(size 0.519938 1.4986)
			(layers "F.Cu" "F.Mask" "F.Paste")
			(net "M_F_CPU0_SB_CB<4>")
		)
		(pad "90" smd rect
			(at -2.050034 17.424908 270)
			(size 0.519938 1.4986)
			(layers "F.Cu" "F.Mask" "F.Paste")
			(net "GND")
		)
		(pad "91" smd rect
			(at -2.050034 18.275046 270)
			(size 0.519938 1.4986)
			(layers "F.Cu" "F.Mask" "F.Paste")
			(net "M_F_CPU0_SB_CB<5>")
		)
		(pad "92" smd rect
			(at -2.050034 19.12493 270)
			(size 0.519938 1.4986)
			(layers "F.Cu" "F.Mask" "F.Paste")
			(net "GND")
		)
		(pad "93" smd rect
			(at -2.050034 19.975068 270)
			(size 0.519938 1.4986)
			(layers "F.Cu" "F.Mask" "F.Paste")
			(net "M_F_CPU0_SB_DQS_DP<9>")
		)
		(pad "94" smd rect
			(at -2.050034 20.824952 270)
			(size 0.519938 1.4986)
			(layers "F.Cu" "F.Mask" "F.Paste")
			(net "M_F_CPU0_SB_DQS_DN<9>")
		)
		(pad "95" smd rect
			(at -2.050034 21.67509 270)
			(size 0.519938 1.4986)
			(layers "F.Cu" "F.Mask" "F.Paste")
			(net "GND")
		)
		(pad "96" smd rect
			(at -2.050034 22.524974 270)
			(size 0.519938 1.4986)
			(layers "F.Cu" "F.Mask" "F.Paste")
			(net "M_F_CPU0_SB_CB<0>")
		)
		(pad "97" smd rect
			(at -2.050034 23.375112 270)
			(size 0.519938 1.4986)
			(layers "F.Cu" "F.Mask" "F.Paste")
			(net "GND")
		)
		(pad "98" smd rect
			(at -2.050034 24.224996 270)
			(size 0.519938 1.4986)
			(layers "F.Cu" "F.Mask" "F.Paste")
			(net "M_F_CPU0_SB_CB<1>")
		)
		(pad "99" smd rect
			(at -2.050034 25.07488 270)
			(size 0.519938 1.4986)
			(layers "F.Cu" "F.Mask" "F.Paste")
			(net "GND")
		)
		(pad "100" smd rect
			(at -2.050034 25.925018 270)
			(size 0.519938 1.4986)
			(layers "F.Cu" "F.Mask" "F.Paste")
			(net "M_F_CPU0_SB_DQ<0>")
		)
		(pad "101" smd rect
			(at -2.050034 26.774902 270)
			(size 0.519938 1.4986)
			(layers "F.Cu" "F.Mask" "F.Paste")
			(net "GND")
		)
		(pad "102" smd rect
			(at -2.050034 27.62504 270)
			(size 0.519938 1.4986)
			(layers "F.Cu" "F.Mask" "F.Paste")
			(net "M_F_CPU0_SB_DQ<1>")
		)
		(pad "103" smd rect
			(at -2.050034 28.474924 270)
			(size 0.519938 1.4986)
			(layers "F.Cu" "F.Mask" "F.Paste")
			(net "GND")
		)
		(pad "104" smd rect
			(at -2.050034 29.325062 270)
			(size 0.519938 1.4986)
			(layers "F.Cu" "F.Mask" "F.Paste")
			(net "M_F_CPU0_SB_DQS_DP<0>")
		)
		(pad "105" smd rect
			(at -2.050034 30.174946 270)
			(size 0.519938 1.4986)
			(layers "F.Cu" "F.Mask" "F.Paste")
			(net "M_F_CPU0_SB_DQS_DN<0>")
		)
		(pad "106" smd rect
			(at -2.050034 31.025084 270)
			(size 0.519938 1.4986)
			(layers "F.Cu" "F.Mask" "F.Paste")
			(net "GND")
		)
		(pad "107" smd rect
			(at -2.050034 31.874968 270)
			(size 0.519938 1.4986)
			(layers "F.Cu" "F.Mask" "F.Paste")
			(net "M_F_CPU0_SB_DQ<4>")
		)
		(pad "108" smd rect
			(at -2.050034 32.725106 270)
			(size 0.519938 1.4986)
			(layers "F.Cu" "F.Mask" "F.Paste")
			(net "GND")
		)
		(pad "109" smd rect
			(at -2.050034 33.57499 270)
			(size 0.519938 1.4986)
			(layers "F.Cu" "F.Mask" "F.Paste")
			(net "M_F_CPU0_SB_DQ<5>")
		)
		(pad "110" smd rect
			(at -2.050034 34.425128 270)
			(size 0.519938 1.4986)
			(layers "F.Cu" "F.Mask" "F.Paste")
			(net "GND")
		)
		(pad "111" smd rect
			(at -2.050034 35.275012 270)
			(size 0.519938 1.4986)
			(layers "F.Cu" "F.Mask" "F.Paste")
			(net "M_F_CPU0_SB_DQ<8>")
		)
		(pad "112" smd rect
			(at -2.050034 36.124896 270)
			(size 0.519938 1.4986)
			(layers "F.Cu" "F.Mask" "F.Paste")
			(net "GND")
		)
	)
)
